(kicad_pcb
	(version 20260206)
	(generator "pcbnew")
	(generator_version "10.0")
	(general
		(thickness 1.21888)
		(legacy_teardrops no)
	)
	(paper "A4")
	(title_block
		(title "timecard-v7 — TimeCard-DC-V7_EXP.PcbDoc")
		(comment 1 "Time Appliance Project (Time Card) / footprints 56-59 of 160")
	)
	(layers
		(0 "F.Cu" signal "TOP")
		(4 "In1.Cu" signal "SGND")
		(6 "In2.Cu" signal "IN1")
		(8 "In3.Cu" signal "IN2")
		(10 "In4.Cu" signal "SGND1")
		(2 "B.Cu" signal "BOTTOM")
		(9 "F.Adhes" user "F.Adhesive")
		(11 "B.Adhes" user "B.Adhesive")
		(13 "F.Paste" user "Top Paste")
		(15 "B.Paste" user "Bottom Paste")
		(5 "F.SilkS" user "Top Overlay")
		(7 "B.SilkS" user "Bottom Overlay")
		(1 "F.Mask" user "Top Solder")
		(3 "B.Mask" user "Bottom Solder")
		(17 "Dwgs.User" user "User.Drawings")
		(19 "Cmts.User" user "User.Comments")
		(21 "Eco1.User" user "User.Eco1")
		(23 "Eco2.User" user "User.Eco2")
		(25 "Edge.Cuts" user)
		(27 "Margin" user)
		(31 "F.CrtYd" user "Top Courtyard")
		(29 "B.CrtYd" user "Bottom Courtyard")
		(35 "F.Fab" user "Top Component Center")
		(33 "B.Fab" user "Bottom Component Center")
	)
	(footprint "FPGA_CONN:SingleFPGAConn"
		(layer "F.Cu")
		(at 162.57841 95.87725 -90)
		(property "Reference" "J35"
			(at -0.368955 -23.428208 270)
			(unlocked yes)
			(layer "F.SilkS")
			(effects
				(font
					(size 1.524 1.524)
					(thickness 0.254)
				)
			)
		)
		(property "Value" "Single FPGA Conn"
			(at 9.27992 3.521202 270)
			(unlocked yes)
			(layer "F.SilkS")
			(hide yes)
			(effects
				(font
					(size 1.524 1.524)
					(thickness 0.254)
				)
			)
		)
		(sheetname "FPGA")
		(sheetfile "FPGA.kicad_sch")
		(duplicate_pad_numbers_are_jumpers no)
		(fp_line
			(start -1.40005 1.24993)
			(end -1.40005 0.70002)
			(stroke
				(width 0.15011)
				(type solid)
			)
			(layer "F.SilkS")
		)
		(fp_line
			(start 1.40004 1.24993)
			(end -1.40005 1.24993)
			(stroke
				(width 0.15011)
				(type solid)
			)
			(layer "F.SilkS")
		)
		(fp_line
			(start 1.40004 1.24993)
			(end 1.40004 0.70002)
			(stroke
				(width 0.15011)
				(type solid)
			)
			(layer "F.SilkS")
		)
		(fp_line
			(start -2 0.70002)
			(end -2 0.03302)
			(stroke
				(width 0.15011)
				(type solid)
			)
			(layer "F.SilkS")
		)
		(fp_line
			(start -1.40005 0.70002)
			(end -2 0.70002)
			(stroke
				(width 0.15011)
				(type solid)
			)
			(layer "F.SilkS")
		)
		(fp_line
			(start 1.99999 0.70002)
			(end 1.40004 0.70002)
			(stroke
				(width 0.15011)
				(type solid)
			)
			(layer "F.SilkS")
		)
		(fp_line
			(start 1.99999 0.70002)
			(end 1.99999 0.03302)
			(stroke
				(width 0.15011)
				(type solid)
			)
			(layer "F.SilkS")
		)
		(fp_line
			(start -2 -20.03298)
			(end -2 -20.69999)
			(stroke
				(width 0.15011)
				(type solid)
			)
			(layer "F.SilkS")
		)
		(fp_line
			(start 1.99999 -20.03298)
			(end 1.99999 -20.69999)
			(stroke
				(width 0.15011)
				(type solid)
			)
			(layer "F.SilkS")
		)
		(fp_line
			(start -1.40005 -20.69999)
			(end -2 -20.69999)
			(stroke
				(width 0.15011)
				(type solid)
			)
			(layer "F.SilkS")
		)
		(fp_line
			(start -1.40005 -20.69999)
			(end -1.40005 -21.2499)
			(stroke
				(width 0.15011)
				(type solid)
			)
			(layer "F.SilkS")
		)
		(fp_line
			(start 1.40004 -20.69999)
			(end 1.40004 -21.2499)
			(stroke
				(width 0.15011)
				(type solid)
			)
			(layer "F.SilkS")
		)
		(fp_line
			(start 1.99999 -20.69999)
			(end 1.40004 -20.69999)
			(stroke
				(width 0.15011)
				(type solid)
			)
			(layer "F.SilkS")
		)
		(fp_line
			(start 1.40004 -21.2499)
			(end -1.40005 -21.2499)
			(stroke
				(width 0.15011)
				(type solid)
			)
			(layer "F.SilkS")
		)
		(fp_circle
			(center 3.5052 -0.22454)
			(end 3.30505 -0.22454)
			(stroke
				(width 0.40005)
				(type solid)
			)
			(fill no)
			(layer "F.SilkS")
		)
		(pad "1" smd rect
			(at 2.02488 -0.24994 270)
			(size 1.54991 0.24994)
			(layers "F.Cu" "F.Mask" "F.Paste")
		)
		(pad "2" smd rect
			(at -2.02489 -0.24994 270)
			(size 1.54991 0.24994)
			(layers "F.Cu" "F.Mask" "F.Paste")
		)
		(pad "3" smd rect
			(at 2.02488 -0.75007 270)
			(size 1.54991 0.24994)
			(layers "F.Cu" "F.Mask" "F.Paste")
		)
		(pad "4" smd rect
			(at -2.02489 -0.75007 270)
			(size 1.54991 0.24994)
			(layers "F.Cu" "F.Mask" "F.Paste")
		)
		(pad "5" smd rect
			(at 2.02488 -1.24994 270)
			(size 1.54991 0.24994)
			(layers "F.Cu" "F.Mask" "F.Paste")
		)
		(pad "6" smd rect
			(at -2.02489 -1.24994 270)
			(size 1.54991 0.24994)
			(layers "F.Cu" "F.Mask" "F.Paste")
		)
		(pad "7" smd rect
			(at 2.02488 -1.75006 270)
			(size 1.54991 0.24994)
			(layers "F.Cu" "F.Mask" "F.Paste")
		)
		(pad "8" smd rect
			(at -2.02489 -1.75006 270)
			(size 1.54991 0.24994)
			(layers "F.Cu" "F.Mask" "F.Paste")
			(net "MAC_USB_PWR")
		)
		(pad "9" smd rect
			(at 2.02488 -2.24994 270)
			(size 1.54991 0.24994)
			(layers "F.Cu" "F.Mask" "F.Paste")
			(net "GND")
		)
		(pad "10" smd rect
			(at -2.02489 -2.24994 270)
			(size 1.54991 0.24994)
			(layers "F.Cu" "F.Mask" "F.Paste")
			(net "GND")
		)
		(pad "11" smd rect
			(at 2.02488 -2.75006 270)
			(size 1.54991 0.24994)
			(layers "F.Cu" "F.Mask" "F.Paste")
			(net "MAC_RF_OUT")
		)
		(pad "12" smd rect
			(at -2.02489 -2.75006 270)
			(size 1.54991 0.24994)
			(layers "F.Cu" "F.Mask" "F.Paste")
		)
		(pad "13" smd rect
			(at 2.02488 -3.24993 270)
			(size 1.54991 0.24994)
			(layers "F.Cu" "F.Mask" "F.Paste")
			(net "MAC_RF_OUT")
		)
		(pad "14" smd rect
			(at -2.02489 -3.24993 270)
			(size 1.54991 0.24994)
			(layers "F.Cu" "F.Mask" "F.Paste")
		)
		(pad "15" smd rect
			(at 2.02488 -3.75006 270)
			(size 1.54991 0.24994)
			(layers "F.Cu" "F.Mask" "F.Paste")
			(net "ANT1_OUT")
		)
		(pad "16" smd rect
			(at -2.02489 -3.75006 270)
			(size 1.54991 0.24994)
			(layers "F.Cu" "F.Mask" "F.Paste")
			(net "ANT3_IN")
		)
		(pad "17" smd rect
			(at 2.02488 -4.24993 270)
			(size 1.54991 0.24994)
			(layers "F.Cu" "F.Mask" "F.Paste")
			(net "ANT2_OUT")
		)
		(pad "18" smd rect
			(at -2.02489 -4.24993 270)
			(size 1.54991 0.24994)
			(layers "F.Cu" "F.Mask" "F.Paste")
			(net "ANT4_IN")
		)
		(pad "19" smd rect
			(at 2.02488 -4.75006 270)
			(size 1.54991 0.24994)
			(layers "F.Cu" "F.Mask" "F.Paste")
			(net "GND")
		)
		(pad "20" smd rect
			(at -2.02489 -4.75006 270)
			(size 1.54991 0.24994)
			(layers "F.Cu" "F.Mask" "F.Paste")
			(net "GND")
		)
		(pad "21" smd rect
			(at 2.02488 -5.24993 270)
			(size 1.54991 0.24994)
			(layers "F.Cu" "F.Mask" "F.Paste")
			(net "ANT1_IN")
		)
		(pad "22" smd rect
			(at -2.02489 -5.24993 270)
			(size 1.54991 0.24994)
			(layers "F.Cu" "F.Mask" "F.Paste")
		)
		(pad "23" smd rect
			(at 2.02488 -5.75006 270)
			(size 1.54991 0.24994)
			(layers "F.Cu" "F.Mask" "F.Paste")
			(net "ANT2_IN")
		)
		(pad "24" smd rect
			(at -2.02489 -5.75006 270)
			(size 1.54991 0.24994)
			(layers "F.Cu" "F.Mask" "F.Paste")
		)
		(pad "25" smd rect
			(at 2.02488 -6.24993 270)
			(size 1.54991 0.24994)
			(layers "F.Cu" "F.Mask" "F.Paste")
			(net "ANT3_OUT")
		)
		(pad "26" smd rect
			(at -2.02489 -6.24993 270)
			(size 1.54991 0.24994)
			(layers "F.Cu" "F.Mask" "F.Paste")
			(net "MAC_TX")
		)
		(pad "27" smd rect
			(at 2.02488 -6.75005 270)
			(size 1.54991 0.24994)
			(layers "F.Cu" "F.Mask" "F.Paste")
			(net "ANT4_OUT")
		)
		(pad "28" smd rect
			(at -2.02489 -6.75005 270)
			(size 1.54991 0.24994)
			(layers "F.Cu" "F.Mask" "F.Paste")
			(net "MAC_RX")
		)
		(pad "29" smd rect
			(at 2.02488 -7.24993 270)
			(size 1.54991 0.24994)
			(layers "F.Cu" "F.Mask" "F.Paste")
			(net "GND")
		)
		(pad "30" smd rect
			(at -2.02489 -7.24993 270)
			(size 1.54991 0.24994)
			(layers "F.Cu" "F.Mask" "F.Paste")
			(net "GND")
		)
		(pad "31" smd rect
			(at 2.02488 -7.75005 270)
			(size 1.54991 0.24994)
			(layers "F.Cu" "F.Mask" "F.Paste")
		)
		(pad "32" smd rect
			(at -2.02489 -7.75005 270)
			(size 1.54991 0.24994)
			(layers "F.Cu" "F.Mask" "F.Paste")
		)
		(pad "33" smd rect
			(at 2.02488 -8.24992 270)
			(size 1.54991 0.24994)
			(layers "F.Cu" "F.Mask" "F.Paste")
			(net "MAC_FREQ_CTRL")
		)
		(pad "34" smd rect
			(at -2.02489 -8.24992 270)
			(size 1.54991 0.24994)
			(layers "F.Cu" "F.Mask" "F.Paste")
		)
		(pad "35" smd rect
			(at 2.02488 -8.75005 270)
			(size 1.54991 0.24994)
			(layers "F.Cu" "F.Mask" "F.Paste")
			(net "MAC_ALARM")
		)
		(pad "36" smd rect
			(at -2.02489 -8.75005 270)
			(size 1.54991 0.24994)
			(layers "F.Cu" "F.Mask" "F.Paste")
		)
		(pad "37" smd rect
			(at 2.02488 -9.24992 270)
			(size 1.54991 0.24994)
			(layers "F.Cu" "F.Mask" "F.Paste")
			(net "MAC_BITE")
		)
		(pad "38" smd rect
			(at -2.02489 -9.24992 270)
			(size 1.54991 0.24994)
			(layers "F.Cu" "F.Mask" "F.Paste")
		)
		(pad "39" smd rect
			(at 2.02488 -9.75005 270)
			(size 1.54991 0.24994)
			(layers "F.Cu" "F.Mask" "F.Paste")
			(net "GND")
		)
		(pad "40" smd rect
			(at -2.02489 -9.75005 270)
			(size 1.54991 0.24994)
			(layers "F.Cu" "F.Mask" "F.Paste")
			(net "GND")
		)
		(pad "41" smd rect
			(at 2.02488 -10.24992 270)
			(size 1.54991 0.24994)
			(layers "F.Cu" "F.Mask" "F.Paste")
		)
		(pad "42" smd rect
			(at -2.02489 -10.24992 270)
			(size 1.54991 0.24994)
			(layers "F.Cu" "F.Mask" "F.Paste")
		)
		(pad "43" smd rect
			(at 2.02488 -10.75005 270)
			(size 1.54991 0.24994)
			(layers "F.Cu" "F.Mask" "F.Paste")
			(net "FPGA_MAC_PPS_OUT-")
		)
		(pad "44" smd rect
			(at -2.02489 -10.75005 270)
			(size 1.54991 0.24994)
			(layers "F.Cu" "F.Mask" "F.Paste")
		)
		(pad "45" smd rect
			(at 2.02488 -11.24992 270)
			(size 1.54991 0.24994)
			(layers "F.Cu" "F.Mask" "F.Paste")
		)
		(pad "46" smd rect
			(at -2.02489 -11.24992 270)
			(size 1.54991 0.24994)
			(layers "F.Cu" "F.Mask" "F.Paste")
		)
		(pad "47" smd rect
			(at 2.02488 -11.75004 270)
			(size 1.54991 0.24994)
			(layers "F.Cu" "F.Mask" "F.Paste")
			(net "FPGA_MAC_PPS_IN0-")
		)
		(pad "48" smd rect
			(at -2.02489 -11.75004 270)
			(size 1.54991 0.24994)
			(layers "F.Cu" "F.Mask" "F.Paste")
		)
		(pad "49" smd rect
			(at 2.02488 -12.24992 270)
			(size 1.54991 0.24994)
			(layers "F.Cu" "F.Mask" "F.Paste")
			(net "GND")
		)
		(pad "50" smd rect
			(at -2.02489 -12.24992 270)
			(size 1.54991 0.24994)
			(layers "F.Cu" "F.Mask" "F.Paste")
			(net "GND")
		)
		(pad "51" smd rect
			(at 2.02488 -12.75004 270)
			(size 1.54991 0.24994)
			(layers "F.Cu" "F.Mask" "F.Paste")
		)
		(pad "52" smd rect
			(at -2.02489 -12.75004 270)
			(size 1.54991 0.24994)
			(layers "F.Cu" "F.Mask" "F.Paste")
		)
		(pad "53" smd rect
			(at 2.02488 -13.24991 270)
			(size 1.54991 0.24994)
			(layers "F.Cu" "F.Mask" "F.Paste")
			(net "FPGA_MAC_PPS_IN1-")
		)
		(pad "54" smd rect
			(at -2.02489 -13.24991 270)
			(size 1.54991 0.24994)
			(layers "F.Cu" "F.Mask" "F.Paste")
		)
		(pad "55" smd rect
			(at 2.02488 -13.75004 270)
			(size 1.54991 0.24994)
			(layers "F.Cu" "F.Mask" "F.Paste")
		)
		(pad "56" smd rect
			(at -2.02489 -13.75004 270)
			(size 1.54991 0.24994)
			(layers "F.Cu" "F.Mask" "F.Paste")
		)
		(pad "57" smd rect
			(at 2.02488 -14.24991 270)
			(size 1.54991 0.24994)
			(layers "F.Cu" "F.Mask" "F.Paste")
		)
		(pad "58" smd rect
			(at -2.02489 -14.24991 270)
			(size 1.54991 0.24994)
			(layers "F.Cu" "F.Mask" "F.Paste")
		)
		(pad "59" smd rect
			(at 2.02488 -14.75004 270)
			(size 1.54991 0.24994)
			(layers "F.Cu" "F.Mask" "F.Paste")
			(net "GND")
		)
		(pad "60" smd rect
			(at -2.02489 -14.75004 270)
			(size 1.54991 0.24994)
			(layers "F.Cu" "F.Mask" "F.Paste")
			(net "GND")
		)
		(pad "61" smd rect
			(at 2.02488 -15.24991 270)
			(size 1.54991 0.24994)
			(layers "F.Cu" "F.Mask" "F.Paste")
			(net "SDA")
		)
		(pad "62" smd rect
			(at -2.02489 -15.24991 270)
			(size 1.54991 0.24994)
			(layers "F.Cu" "F.Mask" "F.Paste")
		)
		(pad "63" smd rect
			(at 2.02488 -15.75004 270)
			(size 1.54991 0.24994)
			(layers "F.Cu" "F.Mask" "F.Paste")
		)
		(pad "64" smd rect
			(at -2.02489 -15.75004 270)
			(size 1.54991 0.24994)
			(layers "F.Cu" "F.Mask" "F.Paste")
		)
		(pad "65" smd rect
			(at 2.02488 -16.24991 270)
			(size 1.54991 0.24994)
			(layers "F.Cu" "F.Mask" "F.Paste")
		)
		(pad "66" smd rect
			(at -2.02489 -16.24991 270)
			(size 1.54991 0.24994)
			(layers "F.Cu" "F.Mask" "F.Paste")
		)
		(pad "67" smd rect
			(at 2.02488 -16.75003 270)
			(size 1.54991 0.24994)
			(layers "F.Cu" "F.Mask" "F.Paste")
			(net "SCL")
		)
		(pad "68" smd rect
			(at -2.02489 -16.75003 270)
			(size 1.54991 0.24994)
			(layers "F.Cu" "F.Mask" "F.Paste")
		)
		(pad "69" smd rect
			(at 2.02488 -17.24991 270)
			(size 1.54991 0.24994)
			(layers "F.Cu" "F.Mask" "F.Paste")
			(net "GND")
		)
		(pad "70" smd rect
			(at -2.02489 -17.24991 270)
			(size 1.54991 0.24994)
			(layers "F.Cu" "F.Mask" "F.Paste")
			(net "GND")
		)
		(pad "71" smd rect
			(at 2.02488 -17.75003 270)
			(size 1.54991 0.24994)
			(layers "F.Cu" "F.Mask" "F.Paste")
			(net "UART1_TXD")
		)
		(pad "72" smd rect
			(at -2.02489 -17.75003 270)
			(size 1.54991 0.24994)
			(layers "F.Cu" "F.Mask" "F.Paste")
			(net "MAC_USB+")
		)
		(pad "73" smd rect
			(at 2.02488 -18.2499 270)
			(size 1.54991 0.24994)
			(layers "F.Cu" "F.Mask" "F.Paste")
		)
		(pad "74" smd rect
			(at -2.02489 -18.2499 270)
			(size 1.54991 0.24994)
			(layers "F.Cu" "F.Mask" "F.Paste")
			(net "MAC_USB-")
		)
		(pad "75" smd rect
			(at 2.02488 -18.75003 270)
			(size 1.54991 0.24994)
			(layers "F.Cu" "F.Mask" "F.Paste")
		)
		(pad "76" smd rect
			(at -2.02489 -18.75003 270)
			(size 1.54991 0.24994)
			(layers "F.Cu" "F.Mask" "F.Paste")
		)
		(pad "77" smd rect
			(at 2.02488 -19.2499 270)
			(size 1.54991 0.24994)
			(layers "F.Cu" "F.Mask" "F.Paste")
			(net "UART1_RXD")
		)
		(pad "78" smd rect
			(at -2.02489 -19.2499 270)
			(size 1.54991 0.24994)
			(layers "F.Cu" "F.Mask" "F.Paste")
		)
		(pad "79" smd rect
			(at 2.02488 -19.75003 270)
			(size 1.54991 0.24994)
			(layers "F.Cu" "F.Mask" "F.Paste")
			(net "GPS1_RX")
		)
		(pad "80" smd rect
			(at -2.02489 -19.75003 270)
			(size 1.54991 0.24994)
			(layers "F.Cu" "F.Mask" "F.Paste")
			(net "GPS1_TX")
		)
		(pad "81" smd rect
			(at 0.01135 1.17625 270)
			(size 1.70002 1.35001)
			(layers "F.Cu" "F.Mask" "F.Paste")
		)
		(pad "82" thru_hole circle
			(at 0 0 270)
			(size 0.55016 0.55016)
			(drill 0.55016)
			(layers "*.Cu" "*.Mask")
			(remove_unused_layers no)
			(thermal_bridge_angle 90)
		)
		(pad "83" thru_hole circle
			(at 0 -19.99996 270)
			(size 0.55016 0.55016)
			(drill 0.55016)
			(layers "*.Cu" "*.Mask")
			(remove_unused_layers no)
			(thermal_bridge_angle 90)
		)
		(pad "84" smd rect
			(at 0.01135 -21.17375 270)
			(size 1.70002 1.35001)
			(layers "F.Cu" "F.Mask" "F.Paste")
		)
	)
	(footprint "Resistors:RESC1608X50N"
		(layer "F.Cu")
		(at 206.3637 81.8662 180)
		(property "Reference" "R9"
			(at -2.427 -0.395345 0)
			(unlocked yes)
			(layer "F.SilkS")
			(effects
				(font
					(size 0.762 0.762)
					(thickness 0.2286)
				)
				(justify left bottom)
			)
		)
		(property "Value" "ERJ-3EKF2201V"
			(at -18.6651 -15.15359 0)
			(unlocked yes)
			(layer "F.SilkS")
			(hide yes)
			(effects
				(font
					(size 1.524 1.524)
					(thickness 0.254)
				)
				(justify left bottom)
			)
		)
		(sheetname "POWER")
		(sheetfile "POWER.kicad_sch")
		(duplicate_pad_numbers_are_jumpers no)
		(fp_line
			(start 0 -0.5)
			(end 0 0.5)
			(stroke
				(width 0.1524)
				(type solid)
			)
			(layer "F.SilkS")
		)
		(pad "1" smd rect
			(at -0.69 0 270)
			(size 1 0.72)
			(layers "F.Cu" "F.Mask" "F.Paste")
			(net "GND")
		)
		(pad "2" smd rect
			(at 0.69 0 270)
			(size 1 0.72)
			(layers "F.Cu" "F.Mask" "F.Paste")
			(net "NetC22_1")
		)
	)
	(footprint "Vault:CAPC1608X87X45ML20T05"
		(layer "F.Cu")
		(at 210.7637 90.4662 90)
		(property "Reference" "C10"
			(at 4.1 1.006655 270)
			(unlocked yes)
			(layer "F.SilkS")
			(effects
				(font
					(size 0.762 0.762)
					(thickness 0.2286)
				)
				(justify left bottom)
			)
		)
		(property "Value" "0.1uF"
			(at -10.71339 4.9073 0)
			(unlocked yes)
			(layer "F.SilkS")
			(hide yes)
			(effects
				(font
					(size 1.524 1.524)
					(thickness 0.254)
				)
				(justify left bottom)
			)
		)
		(sheetname "POWER")
		(sheetfile "POWER.kicad_sch")
		(duplicate_pad_numbers_are_jumpers no)
		(pad "1" smd rect
			(at -0.7 0 180)
			(size 1.1 1.05)
			(layers "F.Cu" "F.Mask" "F.Paste")
			(net "GND")
		)
		(pad "2" smd rect
			(at 0.7 0 180)
			(size 1.1 1.05)
			(layers "F.Cu" "F.Mask" "F.Paste")
			(net "+3.3V")
		)
	)
	(footprint "SamacSys:SOP50P310X90-8N"
		(layer "F.Cu")
		(at 82.3761 109.1162 180)
		(property "Reference" "U12"
			(at 0.2286 2.026931 180)
			(unlocked yes)
			(layer "F.SilkS")
			(effects
				(font
					(size 0.762 0.762)
					(thickness 0.2286)
				)
			)
		)
		(property "Value" "NC7WV125K8X"
			(at 6.233115 2.911602 180)
			(unlocked yes)
			(layer "F.SilkS")
			(hide yes)
			(effects
				(font
					(size 1.524 1.524)
					(thickness 0.254)
				)
			)
		)
		(sheetname "USER_IO")
		(sheetfile "USER_IO.kicad_sch")
		(duplicate_pad_numbers_are_jumpers no)
		(fp_line
			(start 0.8 1)
			(end -0.8 1)
			(stroke
				(width 0.2)
				(type solid)
			)
			(layer "F.SilkS")
		)
		(fp_line
			(start 0.8 -1)
			(end 0.8 1)
			(stroke
				(width 0.2)
				(type solid)
			)
			(layer "F.SilkS")
		)
		(fp_line
			(start 0.8 -1)
			(end -0.8 -1)
			(stroke
				(width 0.2)
				(type solid)
			)
			(layer "F.SilkS")
		)
		(fp_line
			(start -0.8 -1)
			(end -0.8 1)
			(stroke
				(width 0.2)
				(type solid)
			)
			(layer "F.SilkS")
		)
		(fp_line
			(start -1.15 -1.25)
			(end -2 -1.25)
			(stroke
				(width 0.2)
				(type solid)
			)
			(layer "F.SilkS")
		)
		(pad "1" smd rect
			(at -1.575 -0.75 180)
			(size 0.85 0.3)
			(layers "F.Cu" "F.Mask" "F.Paste")
			(net "ANT2_IO_OUT")
		)
		(pad "2" smd rect
			(at -1.575 -0.25 180)
			(size 0.85 0.3)
			(layers "F.Cu" "F.Mask" "F.Paste")
			(net "ANT2_OUT")
		)
		(pad "3" smd rect
			(at -1.575 0.25 180)
			(size 0.85 0.3)
			(layers "F.Cu" "F.Mask" "F.Paste")
			(net "ANT2_IN")
		)
		(pad "4" smd rect
			(at -1.575 0.75 180)
			(size 0.85 0.3)
			(layers "F.Cu" "F.Mask" "F.Paste")
			(net "GND")
		)
		(pad "5" smd rect
			(at 1.575 0.75 180)
			(size 0.85 0.3)
			(layers "F.Cu" "F.Mask" "F.Paste")
			(net "NetR33_1")
		)
		(pad "6" smd rect
			(at 1.575 0.25 180)
			(size 0.85 0.3)
			(layers "F.Cu" "F.Mask" "F.Paste")
			(net "NetR33_1")
		)
		(pad "7" smd rect
			(at 1.575 -0.25 180)
			(size 0.85 0.3)
			(layers "F.Cu" "F.Mask" "F.Paste")
			(net "ANT2_IO_IN")
		)
		(pad "8" smd rect
			(at 1.575 -0.75 180)
			(size 0.85 0.3)
			(layers "F.Cu" "F.Mask" "F.Paste")
			(net "+3.3V")
		)
	)
)
